# S9S_MB_2U (Grand Teton) — schematic netlist excerpt (pin names and nets, part order shuffled) for the footprints in the layout excerpt that follows; sources: Cadence DE-HDL packaged netlist, KiCad conversion of 03242023_DA0F0TMBIJ0_F0T_Motherboard_J_brd_V01_OCP.brd

Q135  MOSFET_NCH_DUAL  PJT138K IC  pkg SOT363XD  page 145
  S1  = GND
  G1  = GPU_3V3IO_RSVD1
  D2  = GPU_3V3IO_RSVD1_ISO
  S2  = GND
  G2  = GPU_3V3IO_RSVD1_N
  D1  = GPU_3V3IO_RSVD1_N

Y1  Q_CRYSTAL  32.768KHZ IC  pkg SMLF  page 179 : \1\ = XTAL_PCH_RTC2_R ; \2\ = XTAL_PCH_RTC1

(kicad_pcb
	(version 20260206)
	(generator "pcbnew")
	(generator_version "10.0")
	(general
		(thickness 1.6)
		(legacy_teardrops no)
	)
	(paper "A4")
	(title_block
		(title "03242023_DA0F0TMBIJ0_F0T_Motherboard_J_brd_V01_OCP.brd")
		(comment 1 "Grand Teton / footprints 3874-3875 of 6105")
	)
	(layers
		(0 "F.Cu" signal "TOP")
		(4 "In1.Cu" signal "GND")
		(6 "In2.Cu" signal "IN1")
		(8 "In3.Cu" signal "GND1")
		(10 "In4.Cu" signal "IN2")
		(12 "In5.Cu" signal "GND2")
		(14 "In6.Cu" signal "IN3")
		(16 "In7.Cu" signal "GND3")
		(18 "In8.Cu" signal "VCC")
		(20 "In9.Cu" signal "VCC1")
		(22 "In10.Cu" signal "GND4")
		(24 "In11.Cu" signal "IN4")
		(26 "In12.Cu" signal "GND5")
		(28 "In13.Cu" signal "IN5")
		(30 "In14.Cu" signal "GND6")
		(32 "In15.Cu" signal "IN6")
		(34 "In16.Cu" signal "GND7")
		(2 "B.Cu" signal "BOTTOM")
		(9 "F.Adhes" user "F.Adhesive")
		(11 "B.Adhes" user "B.Adhesive")
		(13 "F.Paste" user "Package Geometry/Pastemask Top")
		(15 "B.Paste" user "Package Geometry/Pastemask Bottom")
		(5 "F.SilkS" user "Ref Des/Silkscreen Top")
		(7 "B.SilkS" user "Ref Des/Silkscreen Bottom")
		(1 "F.Mask" user "Board Geometry/Soldermask Top")
		(3 "B.Mask" user "Board Geometry/Soldermask Bottom")
		(17 "Dwgs.User" user "User.Drawings")
		(19 "Cmts.User" user "User.Comments")
		(21 "Eco1.User" user "User.Eco1")
		(23 "Eco2.User" user "User.Eco2")
		(25 "Edge.Cuts" user "Board Geometry/Outline")
		(27 "Margin" user)
		(31 "F.CrtYd" user "Package Geometry/Place Bound Top")
		(29 "B.CrtYd" user "Package Geometry/Place Bound Bottom")
		(35 "F.Fab" user "Ref Des/Assembly Top")
		(33 "B.Fab" user "Ref Des/Assembly Bottom")
	)
	(footprint ""
		(layer "F.Cu")
		(at 323.342 -31.0642 135)
		(property "Reference" "Y1"
			(at -0.163979 -3.010002 0)
			(unlocked yes)
			(layer "F.SilkS")
			(effects
				(font
					(size 0.7874 0.5842)
					(thickness 0.1524)
				)
				(justify left)
			)
		)
		(property "Value" ""
			(at 0 0 135)
			(layer "F.Fab")
			(effects
				(font
					(size 1.27 1.27)
				)
			)
		)
		(duplicate_pad_numbers_are_jumpers no)
		(fp_line
			(start 1.904892 -1.04135)
			(end -1.904892 -1.04135)
			(stroke
				(width 0.1524)
				(type default)
			)
			(layer "F.SilkS")
		)
		(fp_line
			(start 1.904892 1.04135)
			(end 1.904892 -1.04135)
			(stroke
				(width 0.1524)
				(type default)
			)
			(layer "F.SilkS")
		)
		(fp_line
			(start -1.904892 -1.04135)
			(end -1.904892 1.04135)
			(stroke
				(width 0.1524)
				(type default)
			)
			(layer "F.SilkS")
		)
		(fp_line
			(start -1.904892 1.04135)
			(end 1.904892 1.04135)
			(stroke
				(width 0.1524)
				(type default)
			)
			(layer "F.SilkS")
		)
		(fp_line
			(start 1.650032 -0.824926)
			(end -1.650032 -0.824926)
			(stroke
				(width 0.1)
				(type default)
			)
			(layer "F.Fab")
		)
		(fp_line
			(start 1.650032 0.824926)
			(end 1.650032 -0.824926)
			(stroke
				(width 0.1)
				(type default)
			)
			(layer "F.Fab")
		)
		(fp_line
			(start -1.650032 -0.824926)
			(end -1.650032 0.824926)
			(stroke
				(width 0.1)
				(type default)
			)
			(layer "F.Fab")
		)
		(fp_line
			(start -1.650032 0.824926)
			(end 1.650032 0.824926)
			(stroke
				(width 0.1)
				(type default)
			)
			(layer "F.Fab")
		)
		(pad "1" smd rect
			(at -1.249934 0 135)
			(size 1.016 1.8034)
			(layers "F.Cu" "F.Mask" "F.Paste")
			(net "XTAL_PCH_RTC2_R")
		)
		(pad "2" smd rect
			(at 1.249934 0 315)
			(size 1.016 1.8034)
			(layers "F.Cu" "F.Mask" "F.Paste")
			(net "XTAL_PCH_RTC1")
		)
		(zone
			(layer "F.Cu")
			(hatch none 0.5)
			(connect_pads
				(clearance 0)
			)
			(min_thickness 0.25)
			(keepout
				(tracks not_allowed)
				(vias allowed)
				(pads allowed)
				(copperpour not_allowed)
				(footprints allowed)
			)
			(placement
				(enabled no)
				(sheetname "")
			)
			(fill
				(thermal_gap 0.5)
				(thermal_bridge_width 0.5)
				(island_removal_mode 0)
			)
			(polygon
				(pts
					(xy 323.157088 -29.901896) (xy 324.504304 -31.249112) (xy 323.526912 -32.226504) (xy 322.179696 -30.879288)
				)
			)
		)
	)
	(footprint ""
		(layer "F.Cu")
		(at 364.879382 -386.46989)
		(property "Reference" "Q135"
			(at 2.24282 0.802132 0)
			(unlocked yes)
			(layer "F.SilkS")
			(effects
				(font
					(size 0.7874 0.5842)
					(thickness 0.1524)
				)
				(justify left)
			)
		)
		(property "Value" ""
			(at 0 0 0)
			(layer "F.Fab")
			(effects
				(font
					(size 1.27 1.27)
				)
			)
		)
		(duplicate_pad_numbers_are_jumpers no)
		(fp_line
			(start -1.332738 -1.100074)
			(end -0.4826 -1.100074)
			(stroke
				(width 0.1524)
				(type default)
			)
			(layer "F.SilkS")
		)
		(fp_line
			(start -1.332738 1.100074)
			(end -1.332738 -1.100074)
			(stroke
				(width 0.1524)
				(type default)
			)
			(layer "F.SilkS")
		)
		(fp_line
			(start -0.4826 -1.100074)
			(end 0 -0.541274)
			(stroke
				(width 0.1524)
				(type default)
			)
			(layer "F.SilkS")
		)
		(fp_line
			(start 0 -0.541274)
			(end 0.4826 -1.100074)
			(stroke
				(width 0.1524)
				(type default)
			)
			(layer "F.SilkS")
		)
		(fp_line
			(start 0.4826 -1.100074)
			(end 1.332738 -1.100074)
			(stroke
				(width 0.1524)
				(type default)
			)
			(layer "F.SilkS")
		)
		(fp_line
			(start 1.332738 -1.100074)
			(end 1.332738 1.100074)
			(stroke
				(width 0.1524)
				(type default)
			)
			(layer "F.SilkS")
		)
		(fp_line
			(start 1.332738 1.100074)
			(end -1.332738 1.100074)
			(stroke
				(width 0.1524)
				(type default)
			)
			(layer "F.SilkS")
		)
		(fp_poly
			(pts
				(xy -2.2352 -1.001014) (xy -1.533144 -0.649986) (xy -2.2352 -0.298958)
			)
			(stroke
				(width 0)
				(type default)
			)
			(fill yes)
			(layer "F.SilkS")
		)
		(fp_line
			(start -0.674878 -1.100074)
			(end 0.674878 -1.100074)
			(stroke
				(width 0.1)
				(type default)
			)
			(layer "F.Fab")
		)
		(fp_line
			(start -0.674878 1.100074)
			(end -0.674878 -1.100074)
			(stroke
				(width 0.1)
				(type default)
			)
			(layer "F.Fab")
		)
		(fp_line
			(start 0.674878 -1.100074)
			(end 0.674878 1.100074)
			(stroke
				(width 0.1)
				(type default)
			)
			(layer "F.Fab")
		)
		(fp_line
			(start 0.674878 1.100074)
			(end -0.674878 1.100074)
			(stroke
				(width 0.1)
				(type default)
			)
			(layer "F.Fab")
		)
		(fp_poly
			(pts
				(xy -2.2352 -0.298958) (xy -2.2352 -1.001014) (xy -1.533144 -0.649986)
			)
			(stroke
				(width 0)
				(type default)
			)
			(fill yes)
			(layer "F.Fab")
		)
		(pad "1" smd rect
			(at -0.94996 -0.649986 90)
			(size 0.4318 0.508)
			(layers "F.Cu" "F.Mask" "F.Paste")
			(net "GND")
		)
		(pad "2" smd rect
			(at -0.94996 0 90)
			(size 0.4318 0.508)
			(layers "F.Cu" "F.Mask" "F.Paste")
			(net "GPU_3V3IO_RSVD1")
		)
		(pad "3" smd rect
			(at -0.94996 0.649986 90)
			(size 0.4318 0.508)
			(layers "F.Cu" "F.Mask" "F.Paste")
			(net "GPU_3V3IO_RSVD1_ISO")
		)
		(pad "4" smd rect
			(at 0.94996 0.649986 90)
			(size 0.4318 0.508)
			(layers "F.Cu" "F.Mask" "F.Paste")
			(net "GND")
		)
		(pad "5" smd rect
			(at 0.94996 0 90)
			(size 0.4318 0.508)
			(layers "F.Cu" "F.Mask" "F.Paste")
			(net "GPU_3V3IO_RSVD1_N")
		)
		(pad "6" smd rect
			(at 0.94996 -0.649986 90)
			(size 0.4318 0.508)
			(layers "F.Cu" "F.Mask" "F.Paste")
			(net "GPU_3V3IO_RSVD1_N")
		)
	)
)
